# BASEBOARD_FAB2 (Tioga Pass) — schematic netlist excerpt (pin names and nets, part order shuffled) for the footprints in the layout excerpt that follows; sources: Cadence DE-HDL packaged netlist, KiCad conversion of Wiwynn_Tioga_Pass_MB.brd

R3M9  RES  100.0K 1% CHIP  pkg 0402  page 116 : A = P2E_SSB_BMC_RX_C_DN ; B = GND
R7P29  RES  51.1 1.0% CHIP  pkg 0402  page 112 : A = XDP_CPU_TCK0 ; B = GND
R1W43  RES  4.75K 1% CHIP  pkg 0402  page 188 : A = P3V3_STBY ; B = FM_GBE1_LVC3_MOD_ABS

(kicad_pcb
	(version 20260206)
	(generator "pcbnew")
	(generator_version "10.0")
	(general
		(thickness 1.6)
		(legacy_teardrops no)
	)
	(paper "A4")
	(title_block
		(title "Wiwynn_Tioga_Pass_MB.brd")
		(comment 1 "Tioga Pass / footprints 2917-2919 of 4770")
	)
	(layers
		(0 "F.Cu" signal "TOP")
		(4 "In1.Cu" signal "L2GND")
		(6 "In2.Cu" signal "L3")
		(8 "In3.Cu" signal "L4GND")
		(10 "In4.Cu" signal "L5")
		(12 "In5.Cu" signal "L6GND")
		(14 "In6.Cu" signal "L7VCC")
		(16 "In7.Cu" signal "L8VCC")
		(18 "In8.Cu" signal "L9GND")
		(20 "In9.Cu" signal "L10")
		(22 "In10.Cu" signal "L11GND")
		(24 "In11.Cu" signal "L12")
		(26 "In12.Cu" signal "L13GND")
		(2 "B.Cu" signal "BOTTOM")
		(9 "F.Adhes" user "F.Adhesive")
		(11 "B.Adhes" user "B.Adhesive")
		(13 "F.Paste" user "Package Geometry/Pastemask Top")
		(15 "B.Paste" user "Package Geometry/Pastemask Bottom")
		(5 "F.SilkS" user "Ref Des/Silkscreen Top")
		(7 "B.SilkS" user "Ref Des/Silkscreen Bottom")
		(1 "F.Mask" user "Board Geometry/Soldermask Top")
		(3 "B.Mask" user "Board Geometry/Soldermask Bottom")
		(17 "Dwgs.User" user "User.Drawings")
		(19 "Cmts.User" user "User.Comments")
		(21 "Eco1.User" user "User.Eco1")
		(23 "Eco2.User" user "User.Eco2")
		(25 "Edge.Cuts" user "Board Geometry/Outline")
		(27 "Margin" user)
		(31 "F.CrtYd" user "Package Geometry/Place Bound Top")
		(29 "B.CrtYd" user "Package Geometry/Place Bound Bottom")
		(35 "F.Fab" user "Ref Des/Assembly Top")
		(33 "B.Fab" user "Ref Des/Assembly Bottom")
	)
	(footprint ""
		(layer "B.Cu")
		(at 446.8876 -62.5856 -90)
		(property "Reference" "R1W43"
			(at 0.8382 -0.67818 270)
			(unlocked yes)
			(layer "B.SilkS")
			(effects
				(font
					(size 0.4064 0.254)
					(thickness 0.1524)
				)
				(justify left mirror)
			)
		)
		(property "Value" ""
			(at 0 0 90)
			(layer "B.Fab")
			(effects
				(font
					(size 1.27 1.27)
				)
				(justify mirror)
			)
		)
		(duplicate_pad_numbers_are_jumpers no)
		(fp_poly
			(pts
				(xy 0.2794 -0.1016) (xy -0.2794 -0.1016) (xy -0.2794 0.9906) (xy 0.2794 0.9906)
			)
			(stroke
				(width 0)
				(type default)
			)
			(fill no)
			(layer "B.CrtYd")
		)
		(fp_line
			(start -0.2794 0.9906)
			(end -0.2794 -0.1016)
			(stroke
				(width 0.1)
				(type default)
			)
			(layer "B.Fab")
		)
		(fp_line
			(start 0.2794 0.9906)
			(end -0.2794 0.9906)
			(stroke
				(width 0.1)
				(type default)
			)
			(layer "B.Fab")
		)
		(fp_line
			(start -0.2794 -0.1016)
			(end 0.2794 -0.1016)
			(stroke
				(width 0.1)
				(type default)
			)
			(layer "B.Fab")
		)
		(fp_line
			(start 0.2794 -0.1016)
			(end 0.2794 0.9906)
			(stroke
				(width 0.1)
				(type default)
			)
			(layer "B.Fab")
		)
		(pad "1" smd rect
			(at 0 0 90)
			(size 0.508 0.508)
			(layers "B.Cu" "B.Mask" "B.Paste")
			(net "P3V3_STBY")
		)
		(pad "2" smd rect
			(at 0 0.889 90)
			(size 0.508 0.508)
			(layers "B.Cu" "B.Mask" "B.Paste")
			(net "FM_GBE1_LVC3_MOD_ABS")
		)
		(zone
			(layer "B.Cu")
			(hatch none 0.5)
			(connect_pads
				(clearance 0)
			)
			(min_thickness 0.25)
			(keepout
				(tracks not_allowed)
				(vias allowed)
				(pads allowed)
				(copperpour not_allowed)
				(footprints allowed)
			)
			(placement
				(enabled no)
				(sheetname "")
			)
			(fill
				(thermal_gap 0.5)
				(thermal_bridge_width 0.5)
				(island_removal_mode 0)
			)
			(polygon
				(pts
					(xy 446.2526 -62.3316) (xy 446.2526 -62.8396) (xy 446.6336 -62.8396) (xy 446.6336 -62.3316)
				)
			)
		)
		(zone
			(layer "B.Cu")
			(hatch none 0.5)
			(connect_pads
				(clearance 0)
			)
			(min_thickness 0.25)
			(keepout
				(tracks allowed)
				(vias not_allowed)
				(pads allowed)
				(copperpour not_allowed)
				(footprints allowed)
			)
			(placement
				(enabled no)
				(sheetname "")
			)
			(fill
				(thermal_gap 0.5)
				(thermal_bridge_width 0.5)
				(island_removal_mode 0)
			)
			(polygon
				(pts
					(xy 446.6336 -62.3316) (xy 446.6336 -62.8396) (xy 446.2526 -62.8396) (xy 446.2526 -62.3316)
				)
			)
		)
	)
	(footprint ""
		(layer "B.Cu")
		(at 129.786888 -64.934338 -90)
		(property "Reference" "R7P29"
			(at 0 0 90)
			(layer "B.SilkS")
			(hide yes)
			(effects
				(font
					(size 1.27 1.27)
				)
				(justify mirror)
			)
		)
		(property "Value" ""
			(at 0 0 90)
			(layer "B.Fab")
			(effects
				(font
					(size 1.27 1.27)
				)
				(justify mirror)
			)
		)
		(duplicate_pad_numbers_are_jumpers no)
		(fp_rect
			(start -0.2794 0.9906)
			(end 0.2794 -0.1016)
			(stroke
				(width 0)
				(type default)
			)
			(fill no)
			(layer "B.CrtYd")
		)
		(fp_line
			(start -0.2794 0.9906)
			(end -0.2794 -0.1016)
			(stroke
				(width 0.1)
				(type default)
			)
			(layer "B.Fab")
		)
		(fp_line
			(start 0.2794 0.9906)
			(end -0.2794 0.9906)
			(stroke
				(width 0.1)
				(type default)
			)
			(layer "B.Fab")
		)
		(fp_line
			(start -0.2794 -0.1016)
			(end 0.2794 -0.1016)
			(stroke
				(width 0.1)
				(type default)
			)
			(layer "B.Fab")
		)
		(fp_line
			(start 0.2794 -0.1016)
			(end 0.2794 0.9906)
			(stroke
				(width 0.1)
				(type default)
			)
			(layer "B.Fab")
		)
		(pad "1" smd rect
			(at 0 0 90)
			(size 0.508 0.508)
			(layers "B.Cu" "B.Mask" "B.Paste")
			(net "XDP_CPU_TCK0")
		)
		(pad "2" smd rect
			(at 0 0.889 90)
			(size 0.508 0.508)
			(layers "B.Cu" "B.Mask" "B.Paste")
			(net "GND")
		)
		(zone
			(layer "B.Cu")
			(hatch none 0.5)
			(connect_pads
				(clearance 0)
			)
			(min_thickness 0.25)
			(keepout
				(tracks allowed)
				(vias not_allowed)
				(pads allowed)
				(copperpour not_allowed)
				(footprints allowed)
			)
			(placement
				(enabled no)
				(sheetname "")
			)
			(fill
				(thermal_gap 0.5)
				(thermal_bridge_width 0.5)
				(island_removal_mode 0)
			)
			(polygon
				(pts
					(xy 129.151888 -65.188338) (xy 129.151888 -64.680338) (xy 129.532888 -64.680338) (xy 129.532888 -65.188338)
				)
			)
		)
		(zone
			(layer "B.Cu")
			(hatch none 0.5)
			(connect_pads
				(clearance 0)
			)
			(min_thickness 0.25)
			(keepout
				(tracks not_allowed)
				(vias allowed)
				(pads allowed)
				(copperpour not_allowed)
				(footprints allowed)
			)
			(placement
				(enabled no)
				(sheetname "")
			)
			(fill
				(thermal_gap 0.5)
				(thermal_bridge_width 0.5)
				(island_removal_mode 0)
			)
			(polygon
				(pts
					(xy 129.151888 -65.188338) (xy 129.151888 -64.680338) (xy 129.532888 -64.680338) (xy 129.532888 -65.188338)
				)
			)
		)
	)
	(footprint ""
		(layer "B.Cu")
		(at 387.5278 -129.99974 180)
		(property "Reference" "R3M9"
			(at 0 0 0)
			(layer "B.SilkS")
			(hide yes)
			(effects
				(font
					(size 1.27 1.27)
				)
				(justify mirror)
			)
		)
		(property "Value" ""
			(at 0 0 0)
			(layer "B.Fab")
			(effects
				(font
					(size 1.27 1.27)
				)
				(justify mirror)
			)
		)
		(duplicate_pad_numbers_are_jumpers no)
		(fp_poly
			(pts
				(xy 0.2794 -0.1016) (xy -0.2794 -0.1016) (xy -0.2794 0.9906) (xy 0.2794 0.9906)
			)
			(stroke
				(width 0)
				(type default)
			)
			(fill no)
			(layer "B.CrtYd")
		)
		(fp_line
			(start 0.2794 0.9906)
			(end -0.2794 0.9906)
			(stroke
				(width 0.1)
				(type default)
			)
			(layer "B.Fab")
		)
		(fp_line
			(start 0.2794 -0.1016)
			(end 0.2794 0.9906)
			(stroke
				(width 0.1)
				(type default)
			)
			(layer "B.Fab")
		)
		(fp_line
			(start -0.2794 0.9906)
			(end -0.2794 -0.1016)
			(stroke
				(width 0.1)
				(type default)
			)
			(layer "B.Fab")
		)
		(fp_line
			(start -0.2794 -0.1016)
			(end 0.2794 -0.1016)
			(stroke
				(width 0.1)
				(type default)
			)
			(layer "B.Fab")
		)
		(pad "1" smd rect
			(at 0 0)
			(size 0.508 0.508)
			(layers "B.Cu" "B.Mask" "B.Paste")
			(net "P2E_SSB_BMC_RX_C_DN")
		)
		(pad "2" smd rect
			(at 0 0.889)
			(size 0.508 0.508)
			(layers "B.Cu" "B.Mask" "B.Paste")
			(net "GND")
		)
		(zone
			(layer "B.Cu")
			(hatch none 0.5)
			(connect_pads
				(clearance 0)
			)
			(min_thickness 0.25)
			(keepout
				(tracks not_allowed)
				(vias allowed)
				(pads allowed)
				(copperpour not_allowed)
				(footprints allowed)
			)
			(placement
				(enabled no)
				(sheetname "")
			)
			(fill
				(thermal_gap 0.5)
				(thermal_bridge_width 0.5)
				(island_removal_mode 0)
			)
			(polygon
				(pts
					(xy 387.2738 -130.63474) (xy 387.7818 -130.63474) (xy 387.7818 -130.25374) (xy 387.2738 -130.25374)
				)
			)
		)
		(zone
			(layer "B.Cu")
			(hatch none 0.5)
			(connect_pads
				(clearance 0)
			)
			(min_thickness 0.25)
			(keepout
				(tracks allowed)
				(vias not_allowed)
				(pads allowed)
				(copperpour not_allowed)
				(footprints allowed)
			)
			(placement
				(enabled no)
				(sheetname "")
			)
			(fill
				(thermal_gap 0.5)
				(thermal_bridge_width 0.5)
				(island_removal_mode 0)
			)
			(polygon
				(pts
					(xy 387.2738 -130.25374) (xy 387.7818 -130.25374) (xy 387.7818 -130.63474) (xy 387.2738 -130.63474)
				)
			)
		)
	)
)
